(kicad_pcb
	(version 20260206)
	(generator "pcbnew")
	(generator_version "10.0")
	(general
		(thickness 1.6)
		(legacy_teardrops no)
	)
	(paper "A4")
	(title_block
		(title "panther-plus-userver — 13130-1b_20150205.brd")
		(comment 1 "Honey Badger (Wiwynn) / footprints 80-86 of 1509")
	)
	(layers
		(0 "F.Cu" signal "TOP")
		(4 "In1.Cu" signal "L2")
		(6 "In2.Cu" signal "L3")
		(8 "In3.Cu" signal "L4")
		(10 "In4.Cu" signal "L5")
		(12 "In5.Cu" signal "L6")
		(14 "In6.Cu" signal "L7")
		(16 "In7.Cu" signal "L8")
		(18 "In8.Cu" signal "L9")
		(20 "In9.Cu" signal "L10")
		(22 "In10.Cu" signal "L11")
		(2 "B.Cu" signal "BOTTOM")
		(9 "F.Adhes" user "F.Adhesive")
		(11 "B.Adhes" user "B.Adhesive")
		(13 "F.Paste" user "Package Geometry/Pastemask Top")
		(15 "B.Paste" user "Package Geometry/Pastemask Bottom")
		(5 "F.SilkS" user "Ref Des/Silkscreen Top")
		(7 "B.SilkS" user "Ref Des/Silkscreen Bottom")
		(1 "F.Mask" user "Board Geometry/Soldermask Top")
		(3 "B.Mask" user "Board Geometry/Soldermask Bottom")
		(17 "Dwgs.User" user "User.Drawings")
		(19 "Cmts.User" user "User.Comments")
		(21 "Eco1.User" user "User.Eco1")
		(23 "Eco2.User" user "User.Eco2")
		(25 "Edge.Cuts" user "Board Geometry/Outline")
		(27 "Margin" user)
		(31 "F.CrtYd" user "Package Geometry/Place Bound Top")
		(29 "B.CrtYd" user "Package Geometry/Place Bound Bottom")
		(35 "F.Fab" user "Ref Des/Assembly Top")
		(33 "B.Fab" user "Ref Des/Assembly Bottom")
	)
	(footprint ""
		(layer "F.Cu")
		(at 13.97 -25.781 -90)
		(property "Reference" "PU7"
			(at 0 0 270)
			(layer "F.SilkS")
			(hide yes)
			(effects
				(font
					(size 1.27 1.27)
				)
			)
		)
		(property "Value" "TPS53319DQPR-GP"
			(at 4.1402 -3.8227 270)
			(unlocked yes)
			(layer "F.Fab")
			(hide yes)
			(effects
				(font
					(size 1.016 1.016)
					(thickness 0.1524)
				)
			)
		)
		(property "Device Type" "QFN22G6050-G6133H60"
			(at 4.1402 -5.3467 270)
			(unlocked yes)
			(layer "F.Fab")
			(hide yes)
			(effects
				(font
					(size 1.016 1.016)
					(thickness 0.1524)
				)
			)
		)
		(duplicate_pad_numbers_are_jumpers no)
		(fp_poly
			(pts
				(xy 2.49301 -2.897124) (xy 2.885186 -3.2893) (xy 2.100834 -3.2893)
			)
			(stroke
				(width 0)
				(type default)
			)
			(fill yes)
			(layer "F.SilkS")
		)
		(fp_rect
			(start -3.2512 2.8829)
			(end 3.2512 -2.8829)
			(stroke
				(width 0)
				(type default)
			)
			(fill no)
			(layer "F.CrtYd")
		)
		(fp_rect
			(start -3.2512 2.8829)
			(end 3.2512 -2.8829)
			(stroke
				(width 0)
				(type default)
			)
			(fill no)
			(layer "F.Fab")
		)
		(pad "1" smd rect
			(at 2.500122 -2.322322 270)
			(size 0.3048 0.8636)
			(layers "F.Cu" "F.Mask" "F.Paste")
			(net "P1V0_VFB")
		)
		(pad "2" smd rect
			(at 1.999996 -2.322322 270)
			(size 0.3048 0.8636)
			(layers "F.Cu" "F.Mask" "F.Paste")
			(net "P1V0_EN")
		)
		(pad "3" smd rect
			(at 1.500124 -2.322322 270)
			(size 0.3048 0.8636)
			(layers "F.Cu" "F.Mask" "F.Paste")
			(net "PG_P1V0")
		)
		(pad "4" smd rect
			(at 0.999998 -2.322322 270)
			(size 0.3048 0.8636)
			(layers "F.Cu" "F.Mask" "F.Paste")
			(net "P1V0_VBST")
		)
		(pad "5" smd rect
			(at 0.500126 -2.322322 270)
			(size 0.3048 0.8636)
			(layers "F.Cu" "F.Mask" "F.Paste")
			(net "P1V0_ROVP")
		)
		(pad "6" smd rect
			(at 0 -2.322322 270)
			(size 0.3048 0.8636)
			(layers "F.Cu" "F.Mask" "F.Paste")
			(net "P1V0_LX")
		)
		(pad "7" smd rect
			(at -0.500126 -2.322322 270)
			(size 0.3048 0.8636)
			(layers "F.Cu" "F.Mask" "F.Paste")
			(net "P1V0_LX")
		)
		(pad "8" smd rect
			(at -0.999998 -2.322322 270)
			(size 0.3048 0.8636)
			(layers "F.Cu" "F.Mask" "F.Paste")
			(net "P1V0_LX")
		)
		(pad "9" smd rect
			(at -1.500124 -2.322322 270)
			(size 0.3048 0.8636)
			(layers "F.Cu" "F.Mask" "F.Paste")
			(net "P1V0_LX")
		)
		(pad "10" smd rect
			(at -1.999996 -2.322322 270)
			(size 0.3048 0.8636)
			(layers "F.Cu" "F.Mask" "F.Paste")
			(net "P1V0_LX")
		)
		(pad "11" smd rect
			(at -2.500122 -2.322322 270)
			(size 0.3048 0.8636)
			(layers "F.Cu" "F.Mask" "F.Paste")
			(net "P1V0_LX")
		)
		(pad "12" smd rect
			(at -2.500122 2.322322 270)
			(size 0.3048 0.8636)
			(layers "F.Cu" "F.Mask" "F.Paste")
			(net "P1V0_VIN")
		)
		(pad "13" smd rect
			(at -1.999996 2.322322 270)
			(size 0.3048 0.8636)
			(layers "F.Cu" "F.Mask" "F.Paste")
			(net "P1V0_VIN")
		)
		(pad "14" smd rect
			(at -1.500124 2.322322 270)
			(size 0.3048 0.8636)
			(layers "F.Cu" "F.Mask" "F.Paste")
			(net "P1V0_VIN")
		)
		(pad "15" smd rect
			(at -0.999998 2.322322 270)
			(size 0.3048 0.8636)
			(layers "F.Cu" "F.Mask" "F.Paste")
			(net "P1V0_VIN")
		)
		(pad "16" smd rect
			(at -0.500126 2.322322 270)
			(size 0.3048 0.8636)
			(layers "F.Cu" "F.Mask" "F.Paste")
			(net "P1V0_VIN")
		)
		(pad "17" smd rect
			(at 0 2.322322 270)
			(size 0.3048 0.8636)
			(layers "F.Cu" "F.Mask" "F.Paste")
			(net "P1V0_VIN")
		)
		(pad "18" smd rect
			(at 0.500126 2.322322 270)
			(size 0.3048 0.8636)
			(layers "F.Cu" "F.Mask" "F.Paste")
			(net "P1V0_VREG")
		)
		(pad "19" smd rect
			(at 0.999998 2.322322 270)
			(size 0.3048 0.8636)
			(layers "F.Cu" "F.Mask" "F.Paste")
			(net "P1V0_VDD")
		)
		(pad "20" smd rect
			(at 1.500124 2.322322 270)
			(size 0.3048 0.8636)
			(layers "F.Cu" "F.Mask" "F.Paste")
			(net "P1V0_MODE")
		)
		(pad "21" smd rect
			(at 1.999996 2.322322 270)
			(size 0.3048 0.8636)
			(layers "F.Cu" "F.Mask" "F.Paste")
			(net "P1V0_TRIP")
		)
		(pad "22" smd rect
			(at 2.500122 2.322322 270)
			(size 0.3048 0.8636)
			(layers "F.Cu" "F.Mask" "F.Paste")
			(net "P1V0_RF")
		)
		(pad "23" smd custom
			(at 0 0 270)
			(size 0.83185 0.83185)
			(layers "F.Cu" "F.Mask" "F.Paste")
			(net "GND")
			(options
				(clearance outline)
				(anchor circle)
			)
			(primitives
				(gr_poly
					(pts
						(xy -2.7813 1.6637) (xy -2.7813 1.2954) (xy -3.048 1.2954) (xy -3.048 0.9525) (xy -2.7813 0.9525)
						(xy -2.7813 -0.9525) (xy -3.048 -0.9525) (xy -3.048 -1.2954) (xy -2.7813 -1.2954) (xy -2.7813 -1.6637)
						(xy 2.7813 -1.6637) (xy 2.7813 -1.2954) (xy 3.048 -1.2954) (xy 3.048 -0.9525) (xy 2.7813 -0.9525)
						(xy 2.7813 0.9525) (xy 3.048 0.9525) (xy 3.048 1.2954) (xy 2.7813 1.2954) (xy 2.7813 1.6637)
					)
					(width 0)
					(fill yes)
				)
			)
		)
	)
	(footprint ""
		(layer "F.Cu")
		(at 130.302 -44.704 -90)
		(property "Reference" "C12"
			(at 0 0 270)
			(layer "F.SilkS")
			(hide yes)
			(effects
				(font
					(size 1.27 1.27)
				)
			)
		)
		(property "Value" "SCD1U10V2KX-5GP"
			(at 1.1811 -2.7051 270)
			(unlocked yes)
			(layer "F.Fab")
			(hide yes)
			(effects
				(font
					(size 1.016 1.016)
					(thickness 0.1524)
				)
			)
		)
		(property "Device Type" "C402H22"
			(at 1.1811 -4.2291 270)
			(unlocked yes)
			(layer "F.Fab")
			(hide yes)
			(effects
				(font
					(size 1.016 1.016)
					(thickness 0.1524)
				)
			)
		)
		(duplicate_pad_numbers_are_jumpers no)
		(fp_rect
			(start -0.381 0.7366)
			(end 0.381 -0.7366)
			(stroke
				(width 0)
				(type default)
			)
			(fill no)
			(layer "F.CrtYd")
		)
		(fp_rect
			(start -0.381 0.7366)
			(end 0.381 -0.7366)
			(stroke
				(width 0)
				(type default)
			)
			(fill no)
			(layer "F.Fab")
		)
		(pad "1" smd custom
			(at 0 -0.4572 270)
			(size 0.1143 0.1143)
			(layers "F.Cu" "F.Mask" "F.Paste")
			(net "P1V2_FPGA_A")
			(options
				(clearance outline)
				(anchor circle)
			)
			(primitives
				(gr_poly
					(pts
						(arc
							(start -0.254 -0.1778)
							(mid -0.239121 -0.213721)
							(end -0.2032 -0.2286)
						)
						(arc
							(start 0.2032 -0.2286)
							(mid 0.239121 -0.213721)
							(end 0.254 -0.1778)
						)
						(arc
							(start 0.254 0.1778)
							(mid 0.239121 0.213721)
							(end 0.2032 0.2286)
						)
						(arc
							(start -0.2032 0.2286)
							(mid -0.239121 0.213721)
							(end -0.254 0.1778)
						)
					)
					(width 0)
					(fill yes)
				)
			)
		)
		(pad "2" smd custom
			(at 0 0.4572 270)
			(size 0.1143 0.1143)
			(layers "F.Cu" "F.Mask" "F.Paste")
			(net "GND")
			(options
				(clearance outline)
				(anchor circle)
			)
			(primitives
				(gr_poly
					(pts
						(arc
							(start -0.254 -0.1778)
							(mid -0.239121 -0.213721)
							(end -0.2032 -0.2286)
						)
						(arc
							(start 0.2032 -0.2286)
							(mid 0.239121 -0.213721)
							(end 0.254 -0.1778)
						)
						(arc
							(start 0.254 0.1778)
							(mid 0.239121 0.213721)
							(end 0.2032 0.2286)
						)
						(arc
							(start -0.2032 0.2286)
							(mid -0.239121 0.213721)
							(end -0.254 0.1778)
						)
					)
					(width 0)
					(fill yes)
				)
			)
		)
	)
	(footprint ""
		(layer "F.Cu")
		(at 197.993 -9.272778)
		(property "Reference" "R391"
			(at 0 0 0)
			(layer "F.SilkS")
			(hide yes)
			(effects
				(font
					(size 1.27 1.27)
				)
			)
		)
		(property "Value" "0R2J-2-GP"
			(at 0.064008 -3.993896 0)
			(unlocked yes)
			(layer "F.Fab")
			(hide yes)
			(effects
				(font
					(size 1.016 1.016)
					(thickness 0.1524)
				)
			)
		)
		(property "Device Type" "R402H16"
			(at 0.064008 -5.517896 0)
			(unlocked yes)
			(layer "F.Fab")
			(hide yes)
			(effects
				(font
					(size 1.016 1.016)
					(thickness 0.1524)
				)
			)
		)
		(duplicate_pad_numbers_are_jumpers no)
		(fp_rect
			(start -0.381 0.8382)
			(end 0.381 -0.8382)
			(stroke
				(width 0)
				(type default)
			)
			(fill no)
			(layer "F.CrtYd")
		)
		(fp_rect
			(start -0.381 0.8382)
			(end 0.381 -0.8382)
			(stroke
				(width 0)
				(type default)
			)
			(fill no)
			(layer "F.Fab")
		)
		(pad "1" smd custom
			(at 0 -0.4318)
			(size 0.127 0.127)
			(layers "F.Cu" "F.Mask" "F.Paste")
			(net "SMB_M_B1_R_DATA")
			(options
				(clearance outline)
				(anchor circle)
			)
			(primitives
				(gr_poly
					(pts
						(arc
							(start -0.2032 -0.2794)
							(mid -0.239121 -0.264521)
							(end -0.254 -0.2286)
						)
						(arc
							(start -0.254 0.2286)
							(mid -0.239121 0.264521)
							(end -0.2032 0.2794)
						)
						(arc
							(start 0.2032 0.2794)
							(mid 0.239121 0.264521)
							(end 0.254 0.2286)
						)
						(arc
							(start 0.254 -0.2286)
							(mid 0.239121 -0.264521)
							(end 0.2032 -0.2794)
						)
					)
					(width 0)
					(fill yes)
				)
			)
		)
		(pad "2" smd custom
			(at 0 0.4318)
			(size 0.127 0.127)
			(layers "F.Cu" "F.Mask" "F.Paste")
			(net "SMB_HOST_LV_DATA")
			(options
				(clearance outline)
				(anchor circle)
			)
			(primitives
				(gr_poly
					(pts
						(arc
							(start -0.2032 -0.2794)
							(mid -0.239121 -0.264521)
							(end -0.254 -0.2286)
						)
						(arc
							(start -0.254 0.2286)
							(mid -0.239121 0.264521)
							(end -0.2032 0.2794)
						)
						(arc
							(start 0.2032 0.2794)
							(mid 0.239121 0.264521)
							(end 0.254 0.2286)
						)
						(arc
							(start 0.254 -0.2286)
							(mid 0.239121 -0.264521)
							(end 0.2032 -0.2794)
						)
					)
					(width 0)
					(fill yes)
				)
			)
		)
	)
	(footprint ""
		(layer "F.Cu")
		(at 70.358 -57.6072)
		(property "Reference" "C78"
			(at 0 0 0)
			(layer "F.SilkS")
			(hide yes)
			(effects
				(font
					(size 1.27 1.27)
				)
			)
		)
		(property "Value" "SCD1U16V2KX-3GP"
			(at 1.8923 -1.2065 0)
			(unlocked yes)
			(layer "F.Fab")
			(hide yes)
			(effects
				(font
					(size 1.016 1.016)
					(thickness 0.1524)
				)
			)
		)
		(property "Device Type" "C402H22"
			(at 1.8923 -2.7305 0)
			(unlocked yes)
			(layer "F.Fab")
			(hide yes)
			(effects
				(font
					(size 1.016 1.016)
					(thickness 0.1524)
				)
			)
		)
		(duplicate_pad_numbers_are_jumpers no)
		(fp_rect
			(start -0.381 0.7366)
			(end 0.381 -0.7366)
			(stroke
				(width 0)
				(type default)
			)
			(fill no)
			(layer "F.CrtYd")
		)
		(fp_rect
			(start -0.381 0.7366)
			(end 0.381 -0.7366)
			(stroke
				(width 0)
				(type default)
			)
			(fill no)
			(layer "F.Fab")
		)
		(pad "1" smd custom
			(at 0 -0.4572)
			(size 0.1143 0.1143)
			(layers "F.Cu" "F.Mask" "F.Paste")
			(net "P1V8_SENSE")
			(options
				(clearance outline)
				(anchor circle)
			)
			(primitives
				(gr_poly
					(pts
						(arc
							(start -0.254 -0.1778)
							(mid -0.239121 -0.213721)
							(end -0.2032 -0.2286)
						)
						(arc
							(start 0.2032 -0.2286)
							(mid 0.239121 -0.213721)
							(end 0.254 -0.1778)
						)
						(arc
							(start 0.254 0.1778)
							(mid 0.239121 0.213721)
							(end 0.2032 0.2286)
						)
						(arc
							(start -0.2032 0.2286)
							(mid -0.239121 0.213721)
							(end -0.254 0.1778)
						)
					)
					(width 0)
					(fill yes)
				)
			)
		)
		(pad "2" smd custom
			(at 0 0.4572)
			(size 0.1143 0.1143)
			(layers "F.Cu" "F.Mask" "F.Paste")
			(net "GND")
			(options
				(clearance outline)
				(anchor circle)
			)
			(primitives
				(gr_poly
					(pts
						(arc
							(start -0.254 -0.1778)
							(mid -0.239121 -0.213721)
							(end -0.2032 -0.2286)
						)
						(arc
							(start 0.2032 -0.2286)
							(mid 0.239121 -0.213721)
							(end 0.254 -0.1778)
						)
						(arc
							(start 0.254 0.1778)
							(mid 0.239121 0.213721)
							(end 0.2032 0.2286)
						)
						(arc
							(start -0.2032 0.2286)
							(mid -0.239121 0.213721)
							(end -0.254 0.1778)
						)
					)
					(width 0)
					(fill yes)
				)
			)
		)
	)
	(footprint ""
		(layer "F.Cu")
		(at 81.026 -65.913)
		(property "Reference" "R186"
			(at 0 0 0)
			(layer "F.SilkS")
			(hide yes)
			(effects
				(font
					(size 1.27 1.27)
				)
			)
		)
		(property "Value" "4K7R2F-GP"
			(at 0.064008 -3.993896 0)
			(unlocked yes)
			(layer "F.Fab")
			(hide yes)
			(effects
				(font
					(size 1.016 1.016)
					(thickness 0.1524)
				)
			)
		)
		(property "Device Type" "R402H16"
			(at 0.064008 -5.517896 0)
			(unlocked yes)
			(layer "F.Fab")
			(hide yes)
			(effects
				(font
					(size 1.016 1.016)
					(thickness 0.1524)
				)
			)
		)
		(duplicate_pad_numbers_are_jumpers no)
		(fp_rect
			(start -0.381 0.8382)
			(end 0.381 -0.8382)
			(stroke
				(width 0)
				(type default)
			)
			(fill no)
			(layer "F.CrtYd")
		)
		(fp_rect
			(start -0.381 0.8382)
			(end 0.381 -0.8382)
			(stroke
				(width 0)
				(type default)
			)
			(fill no)
			(layer "F.Fab")
		)
		(pad "1" smd custom
			(at 0 -0.4318)
			(size 0.127 0.127)
			(layers "F.Cu" "F.Mask" "F.Paste")
			(net "P3V3_STBY")
			(options
				(clearance outline)
				(anchor circle)
			)
			(primitives
				(gr_poly
					(pts
						(arc
							(start -0.2032 -0.2794)
							(mid -0.239121 -0.264521)
							(end -0.254 -0.2286)
						)
						(arc
							(start -0.254 0.2286)
							(mid -0.239121 0.264521)
							(end -0.2032 0.2794)
						)
						(arc
							(start 0.2032 0.2794)
							(mid 0.239121 0.264521)
							(end 0.254 0.2286)
						)
						(arc
							(start 0.254 -0.2286)
							(mid 0.239121 -0.264521)
							(end 0.2032 -0.2794)
						)
					)
					(width 0)
					(fill yes)
				)
			)
		)
		(pad "2" smd custom
			(at 0 0.4318)
			(size 0.127 0.127)
			(layers "F.Cu" "F.Mask" "F.Paste")
			(net "VOL1_SEN_ADDR0")
			(options
				(clearance outline)
				(anchor circle)
			)
			(primitives
				(gr_poly
					(pts
						(arc
							(start -0.2032 -0.2794)
							(mid -0.239121 -0.264521)
							(end -0.254 -0.2286)
						)
						(arc
							(start -0.254 0.2286)
							(mid -0.239121 0.264521)
							(end -0.2032 0.2794)
						)
						(arc
							(start 0.2032 0.2794)
							(mid 0.239121 0.264521)
							(end 0.254 0.2286)
						)
						(arc
							(start 0.254 -0.2286)
							(mid 0.239121 -0.264521)
							(end 0.2032 -0.2794)
						)
					)
					(width 0)
					(fill yes)
				)
			)
		)
	)
	(footprint ""
		(layer "F.Cu")
		(at 8.509 -62.738 90)
		(property "Reference" "C196"
			(at 0 0 90)
			(layer "F.SilkS")
			(hide yes)
			(effects
				(font
					(size 1.27 1.27)
				)
			)
		)
		(property "Value" "SCD1U16V2KX-3GP"
			(at 1.1811 -2.7051 90)
			(unlocked yes)
			(layer "F.Fab")
			(hide yes)
			(effects
				(font
					(size 1.016 1.016)
					(thickness 0.1524)
				)
			)
		)
		(property "Device Type" "C402H22"
			(at 1.1811 -4.2291 90)
			(unlocked yes)
			(layer "F.Fab")
			(hide yes)
			(effects
				(font
					(size 1.016 1.016)
					(thickness 0.1524)
				)
			)
		)
		(duplicate_pad_numbers_are_jumpers no)
		(fp_rect
			(start -0.381 0.7366)
			(end 0.381 -0.7366)
			(stroke
				(width 0)
				(type default)
			)
			(fill no)
			(layer "F.CrtYd")
		)
		(fp_rect
			(start -0.381 0.7366)
			(end 0.381 -0.7366)
			(stroke
				(width 0)
				(type default)
			)
			(fill no)
			(layer "F.Fab")
		)
		(pad "1" smd custom
			(at 0 -0.4572 90)
			(size 0.1143 0.1143)
			(layers "F.Cu" "F.Mask" "F.Paste")
			(net "P2E_CPU_NGFF_TX_DP15")
			(options
				(clearance outline)
				(anchor circle)
			)
			(primitives
				(gr_poly
					(pts
						(arc
							(start -0.254 -0.1778)
							(mid -0.239121 -0.213721)
							(end -0.2032 -0.2286)
						)
						(arc
							(start 0.2032 -0.2286)
							(mid 0.239121 -0.213721)
							(end 0.254 -0.1778)
						)
						(arc
							(start 0.254 0.1778)
							(mid 0.239121 0.213721)
							(end 0.2032 0.2286)
						)
						(arc
							(start -0.2032 0.2286)
							(mid -0.239121 0.213721)
							(end -0.254 0.1778)
						)
					)
					(width 0)
					(fill yes)
				)
			)
		)
		(pad "2" smd custom
			(at 0 0.4572 90)
			(size 0.1143 0.1143)
			(layers "F.Cu" "F.Mask" "F.Paste")
			(net "P2E_CPU_NGFF_C_TX_DP15")
			(options
				(clearance outline)
				(anchor circle)
			)
			(primitives
				(gr_poly
					(pts
						(arc
							(start -0.254 -0.1778)
							(mid -0.239121 -0.213721)
							(end -0.2032 -0.2286)
						)
						(arc
							(start 0.2032 -0.2286)
							(mid 0.239121 -0.213721)
							(end 0.254 -0.1778)
						)
						(arc
							(start 0.254 0.1778)
							(mid 0.239121 0.213721)
							(end 0.2032 0.2286)
						)
						(arc
							(start -0.2032 0.2286)
							(mid -0.239121 0.213721)
							(end -0.254 0.1778)
						)
					)
					(width 0)
					(fill yes)
				)
			)
		)
	)
	(footprint ""
		(layer "F.Cu")
		(at 79.883 -65.913)
		(property "Reference" "R183"
			(at 0 0 0)
			(layer "F.SilkS")
			(hide yes)
			(effects
				(font
					(size 1.27 1.27)
				)
			)
		)
		(property "Value" "4K7R2F-GP"
			(at 1.7907 -1.1176 0)
			(unlocked yes)
			(layer "F.Fab")
			(hide yes)
			(effects
				(font
					(size 1.016 1.016)
					(thickness 0.1524)
				)
			)
		)
		(property "Device Type" "R402H16"
			(at 1.7907 -2.6416 0)
			(unlocked yes)
			(layer "F.Fab")
			(hide yes)
			(effects
				(font
					(size 1.016 1.016)
					(thickness 0.1524)
				)
			)
		)
		(duplicate_pad_numbers_are_jumpers no)
		(fp_rect
			(start -0.381 0.8382)
			(end 0.381 -0.8382)
			(stroke
				(width 0)
				(type default)
			)
			(fill no)
			(layer "F.CrtYd")
		)
		(fp_rect
			(start -0.381 0.8382)
			(end 0.381 -0.8382)
			(stroke
				(width 0)
				(type default)
			)
			(fill no)
			(layer "F.Fab")
		)
		(pad "1" smd custom
			(at 0 -0.4318)
			(size 0.127 0.127)
			(layers "F.Cu" "F.Mask" "F.Paste")
			(net "P3V3_STBY")
			(options
				(clearance outline)
				(anchor circle)
			)
			(primitives
				(gr_poly
					(pts
						(arc
							(start -0.2032 -0.2794)
							(mid -0.239121 -0.264521)
							(end -0.254 -0.2286)
						)
						(arc
							(start -0.254 0.2286)
							(mid -0.239121 0.264521)
							(end -0.2032 0.2794)
						)
						(arc
							(start 0.2032 0.2794)
							(mid 0.239121 0.264521)
							(end 0.254 0.2286)
						)
						(arc
							(start 0.254 -0.2286)
							(mid 0.239121 -0.264521)
							(end 0.2032 -0.2794)
						)
					)
					(width 0)
					(fill yes)
				)
			)
		)
		(pad "2" smd custom
			(at 0 0.4318)
			(size 0.127 0.127)
			(layers "F.Cu" "F.Mask" "F.Paste")
			(net "VOL1_SEN_ADDR1")
			(options
				(clearance outline)
				(anchor circle)
			)
			(primitives
				(gr_poly
					(pts
						(arc
							(start -0.2032 -0.2794)
							(mid -0.239121 -0.264521)
							(end -0.254 -0.2286)
						)
						(arc
							(start -0.254 0.2286)
							(mid -0.239121 0.264521)
							(end -0.2032 0.2794)
						)
						(arc
							(start 0.2032 0.2794)
							(mid 0.239121 0.264521)
							(end 0.254 0.2286)
						)
						(arc
							(start 0.254 -0.2286)
							(mid 0.239121 -0.264521)
							(end 0.2032 -0.2794)
						)
					)
					(width 0)
					(fill yes)
				)
			)
		)
	)
)
